FILE_TYPE = CONNECTIVITY;
{Allegro Design Entry HDL 17.2-2016 S081 (4005846) 1/11/2022}
"PAGE_NUMBER" = 236;
0"NC";
1"P12V_AUX\g";
2"P3V3_AUX\g";
3"P3V3_AUX\g";
4"P12V_AUX\g";
5"P12V_OCP_SFF\g";
6"P3V3_AUX\g";
7"P3V3_OCP_SFF_R\g";
8"GND\g";
9"GND\g";
10"GND\g";
11"GND\g";
12"GND\g";
13"GND\g";
14"GND\g";
15"GND\g";
16"GND\g";
17"GND\g";
18"GND\g";
19"GND\g";
20"GND\g";
21"GND\g";
22"GND\g";
23"HP_LVC3_OCP_V3_1_P12V_PWRGD";
24"P12V_OCP_IMON_1";
25"P12V_OCP_OV_FB_1";
26"P12V_OCP_SFF_ISENSE_MPS_TIC";
27"P12V_OCP_SFF_ISENSE_MPS_MAM";
28"P12V_OCP_AVIN_PD_1";
29"P12V_OCP_AVIN_PD_1";
30"P12V_OCP_FLTB_1";
31"P12V_OCP_EN_1_R2";
32"P12V_OCP_TIMER_1";
33"P12V_OCP_ISET_1";
34"P12V_OCP_SS_1";
35"HP_LVC3_OCP_V3_1_EN";
36"P3V3_OCP_DVDT_1";
37"P3V3_OCP_GATE_1";
38"P3V3_OCP_ILIMIT_1";
39"P3V3_OCP_MODE_1";
40"HP_LVC3_OCP_V3_1_EN";
41"P3V3_OCP_EN_1_R2";
%"UNIVERSAL_GND"
"1","(-4275,11925)","0","logical_power","I41";
;
CDS_LIB"logical_power"
HDL_POWER"GND";
"A"17;
%"Q_CAP"
"1","(-4275,12300)","0","pure_quanta","I42";
;
PART_NUMBER"CH0396J0B04"
VOLTAGE"50V"
VALUE"39PF"
ROOM"NIC1_P3V3_BOM2"
MATERIAL"EMPTY"
PACK_TYPE"C0402"
LOCATION"PC2157"
CDS_LIB"pure_quanta"
TOLERANCE"5%"
$SEC"1"
CDS_SEC"1";
"B"
$PN"2"17;
"A"
$PN"1"39;
%"Q_RES"
"2","(-3825,12300)","0","pure_quanta","I43";
;
PART_NUMBER"CS37152FB05"
PACK_TYPE"0402LF"
TOLERANCE"1%"
VALUE"71.5K"
ROOM"NIC1_P3V3_BOM2"
MATERIAL"EMPTY"
LOCATION"PR3844"
WATTAGE"1/16W"
CDS_LIB"pure_quanta"
$SEC"1"
CDS_SEC"1";
"A"
$PN"1"39;
"B"
$PN"2"17;
%"UNIVERSAL_GND"
"1","(-3525,11925)","0","logical_power","I44";
;
CDS_LIB"logical_power"
HDL_POWER"GND";
"A"18;
%"Q_RES"
"1","(-3525,12250)","1","pure_quanta","I45";
;
PART_NUMBER"CS21332FB05"
VALUE"1.33K"
ROOM"NIC1_P3V3_BOM2"
MATERIAL"EMPTY"
PACK_TYPE"0402LF"
TOLERANCE"1%"
LOCATION"PR3846"
WATTAGE"1/16W"
CDS_LIB"pure_quanta"
$SEC"1"
CDS_SEC"1";
"B"
$PN"2"38;
"A"
$PN"1"18;
%"Q_RES"
"1","(-3775,12600)","0","pure_quanta","I46";
;
PART_NUMBER"CS00002JB13"
TOLERANCE"5%"
VALUE"0"
PACK_TYPE"0402LF"
WATTAGE"1/16W"
MATERIAL"EMPTY"
ROOM"NIC1_P3V3_BOM2"
LOCATION"R3845"
CDS_LIB"pure_quanta"
$SEC"1"
CDS_SEC"1";
"B"
$PN"2"41;
"A"
$PN"1"40;
%"UNIVERSAL_GND"
"1","(-3550,12650)","0","logical_power","I47";
;
HDL_POWER"GND"
CDS_LIB"logical_power";
"A"19;
%"UNIVERSAL_GND"
"1","(-2975,11925)","0","logical_power","I48";
;
CDS_LIB"logical_power"
HDL_POWER"GND";
"A"20;
%"Q_CAP"
"1","(-2975,12225)","0","pure_quanta","I49";
;
PART_NUMBER"CH3683K1B09"
MATERIAL"EMPTY"
VALUE"0.068UF"
VOLTAGE"16V"
PACK_TYPE"0402"
ROOM"NIC1_P3V3_BOM2"
LOCATION"PC2161"
TOLERANCE"10%"
CDS_LIB"pure_quanta"
$SEC"1"
CDS_SEC"1";
"B"
$PN"2"20;
"A"
$PN"1"36;
%"MP5016GQHLZ"
"1","(-2325,12550)","0","pure_quanta","I50";
;
PART_NUMBER"AL005016007"
PART_TYPE"SMLF"
MATERIAL"EMPTY"
VALUE"MP5016GQH-L-Z"
ROOM"NIC1_P3V3_BOM2"
LOCATION"PU205"
CDS_LIB"pure_quanta"
CDS_LMAN_SYM_OUTLINE"-250,200,250,-200"
NEEDS_NO_SIZE"TRUE"
$SEC"1"
CDS_SEC"1";
"SOURCE"
$PN"6_7"7;
"GATE"
$PN"8"37;
"DV_DT"
$PN"10"36;
"VCC"
$PN"1_2"6;
"GND"
$PN"3"21;
"ILIMIT"
$PN"4"38;
"MODE"
$PN"5"39;
"EN"
$PN"9"41;
%"UNIVERSAL_GND"
"1","(-1475,11800)","0","logical_power","I51";
;
CDS_LIB"logical_power"
HDL_POWER"GND";
"A"21;
%"Q_CAP"
"1","(-1475,12150)","0","pure_quanta","I52";
;
PART_NUMBER"CH11006JB18"
VOLTAGE"50V"
VALUE"100PF"
PACK_TYPE"0402"
MATERIAL"EMPTY"
TOLERANCE"5%"
ROOM"NIC1_P3V3_BOM2"
LOCATION"PC2162"
CDS_LIB"pure_quanta"
$SEC"1"
CDS_SEC"1";
"B"
$PN"2"21;
"A"
$PN"1"37;
%"UNIVERSAL_GND"
"1","(-875,12025)","0","logical_power","I53";
;
CDS_LIB"logical_power"
HDL_POWER"GND";
"A"22;
%"Q_CAP"
"1","(-875,12375)","0","pure_quanta","I54";
;
PART_NUMBER"CH6103KEA01"
VOLTAGE"16V"
PACK_TYPE"C0805"
MATERIAL"EMPTY"
ROOM"NIC1_P3V3_BOM2"
VALUE"10UF"
LOCATION"PC2163"
TOLERANCE"10%"
CDS_LIB"pure_quanta"
$SEC"1"
CDS_SEC"1";
"B"
$PN"2"22;
"A"
$PN"1"7;
%"Q_CAP"
"1","(-3550,12875)","0","pure_quanta","I55";
;
PART_NUMBER"CH5104KEB02"
ROOM"NIC1_P3V3_BOM2"
PACK_TYPE"C0402"
VOLTAGE"25V"
MATERIAL"EMPTY"
VALUE"1UF"
LOCATION"PC2159"
CDS_LIB"pure_quanta"
TOLERANCE"10%"
$SEC"1"
CDS_SEC"1";
"B"
$PN"2"19;
"A"
$PN"1"6;
%"UNIVERSAL_POWER"
"1","(-3550,13200)","2","logical_power","I56";
;
HDL_POWER"P3V3_AUX"
CDS_LIB"logical_power";
"A"6;
%"UNIVERSAL_POWER"
"1","(-875,13025)","2","logical_power","I57";
;
HDL_POWER"P3V3_OCP_SFF_R"
CDS_LIB"logical_power";
"A"7;
%"GND"
"1","(-8050,8850)","0","logical_power","I59";
;
HDL_POWER"GND"
SIZE"1B"
CDS_LIB"logical_power";
"A<SIZE-1..0>\NAC"8;
%"Q_CAP"
"1","(-8050,9200)","0","pure_quanta","I60";
;
PART_NUMBER"CH4223K1B00"
VALUE"0.22UF"
MATERIAL"X7R"
PACK_TYPE"0402"
ROOM"NIC1_P12V_MPS_MAM_BOM3"
VOLTAGE"16V"
LOCATION"PC2153"
ROOM1"NIC1_P12V_MPS_TIC_BOM4"
CDS_LIB"pure_quanta"
TOLERANCE"10%"
$SEC"1"
CDS_SEC"1";
"B"
$PN"2"8;
"A"
$PN"1"32;
%"GND"
"1","(-7625,8775)","0","logical_power","I61";
;
HDL_POWER"GND"
SIZE"1B"
CDS_LIB"logical_power";
"A<SIZE-1..0>\NAC"9;
%"Q_RES"
"2","(-7625,9075)","0","pure_quanta","I62";
;
PART_NUMBER"CS31432FB02"
VALUE"14.3K"
TOLERANCE"1%"
WATTAGE"1/16W"
MATERIAL"CHIP"
ROOM"NIC1_P12V_MPS_MAM_BOM3"
PACK_TYPE"0402LF"
LOCATION"PR3835"
ROOM1"NIC1_P12V_MPS_TIC_BOM4"
CDS_LIB"pure_quanta"
$SEC"1"
CDS_SEC"1";
"A"
$PN"1"33;
"B"
$PN"2"9;
%"Q_CAP"
"1","(-7225,8975)","0","pure_quanta","I63";
;
PART_NUMBER"CH3474K1B04"
ROOM"NIC1_P12V_MPS_MAM_BOM3"
VALUE"0.047UF"
VOLTAGE"25V"
PACK_TYPE"C0402"
MATERIAL"X7R"
LOCATION"PC2155"
ROOM1"NIC1_P12V_MPS_TIC_BOM4"
CDS_LIB"pure_quanta"
TOLERANCE"10%"
$SEC"1"
CDS_SEC"1";
"B"
$PN"2"10;
"A"
$PN"1"34;
%"GND"
"1","(-7225,8750)","0","logical_power","I64";
;
HDL_POWER"GND"
SIZE"1B"
CDS_LIB"logical_power";
"A<SIZE-1..0>\NAC"10;
%"Q_RES"
"1","(-7750,9650)","0","pure_quanta","I65";
;
PART_NUMBER"CS00002JB13"
ROOM"NIC1_P12V_MPS_MAM_BOM3"
PACK_TYPE"0402LF"
WATTAGE"1/16W"
TOLERANCE"5%"
VALUE"0"
MATERIAL"CHIP"
$LOCATION"R3834"
ROOM1"NIC1_P12V_MPS_TIC_BOM4"
CDS_LIB"pure_quanta"
CDS_LOCATION"R3834"
$SEC"1"
CDS_SEC"1";
"B"
$PN"2"31;
"A"
$PN"1"35;
%"GND"
"1","(-7625,9400)","0","logical_power","I66";
;
HDL_POWER"GND"
CDS_LIB"logical_power"
SIZE"1B";
"A<SIZE-1..0>\NAC"11;
%"GND"
"1","(-7300,9825)","0","logical_power","I67";
;
HDL_POWER"GND"
SIZE"1B"
CDS_LIB"logical_power";
"A<SIZE-1..0>\NAC"12;
%"Q_CAP"
"1","(-7300,10050)","0","pure_quanta","I68";
;
PART_NUMBER"CH5104KEB02"
ROOM"NIC1_P12V_MPS_MAM_BOM3"
PACK_TYPE"C0402"
VALUE"1UF"
VOLTAGE"25V"
MATERIAL"X6S"
LOCATION"PC2154"
ROOM1"NIC1_P12V_MPS_TIC_BOM4"
CDS_LIB"pure_quanta"
TOLERANCE"10%"
$SEC"1"
CDS_SEC"1";
"B"
$PN"2"12;
"A"
$PN"1"1;
%"GND"
"1","(-6884,8916)","0","logical_power","I69";
;
HDL_POWER"GND"
SIZE"1B"
CDS_LIB"logical_power";
"A<SIZE-1..0>\NAC"13;
%"RS31312R"
"1","(-6425,9525)","0","pure_quanta","I70";
;
PART_NUMBER"AL031312000"
MATERIAL"IC"
ROOM"NIC1_P12V_MPS_MAM_BOM3"
VALUE"RS31312R"
LOCATION"PU204"
PART_TYPE"SMLF"
CDS_LIB"pure_quanta"
NEEDS_NO_SIZE"TRUE"
CDS_LMAN_SYM_OUTLINE"-250,525,250,-525"
ROOM1"NIC1_P12V_MPS_TIC_BOM4"
$SEC"1"
CDS_SEC"1";
"GND"
$PN"7"13;
"SS"
$PN"6"34;
"ISET"
$PN"5"33;
"TIMER"
$PN"4"32;
"ENTM"
$PN"3"11;
"LOADEN"
$PN"2"11;
"EN"
$PN"1"31;
"VIN_26"
$PN"26"1;
"VIN_25"
$PN"25"1;
"VIN_24"
$PN"24"1;
"VIN_23"
$PN"23"1;
"IMON"
$PN"8"24;
"FLTB"
$PN"9"30;
"PG"
$PN"10"23;
"OV"
$PN"11"25;
"VOUT_13"
$PN"13"5;
"AVIN"
$PN"12"29;
"VOUT_14"
$PN"14"5;
"VOUT_15"
$PN"15"5;
"VOUT_16"
$PN"16"5;
"VOUT_17"
$PN"17"5;
"VOUT_18"
$PN"18"5;
"VOUT_19"
$PN"19"5;
"VIN_21_22"
$PN"21_22"1;
"VOUT_20"
$PN"20"5;
%"UNIVERSAL_POWER"
"1","(-7300,10400)","0","logical_power","I71";
;
HDL_POWER"P12V_AUX"
CDS_LIB"logical_power";
"A"1;
%"Q_RES"
"2","(-5800,8775)","0","pure_quanta","I72";
;
PART_NUMBER"CS31742FB04"
PACK_TYPE"0402LF"
VALUE"17.4K"
MATERIAL"CHIP"
WATTAGE"1/16W"
TOLERANCE"1%"
ROOM"NIC1_P12V_MPS_MAM_BOM3"
LOCATION"PR3837"
ROOM1"NIC1_P12V_MPS_TIC_BOM4"
CDS_LIB"pure_quanta"
$SEC"1"
CDS_SEC"1";
"A"
$PN"1"24;
"B"
$PN"2"14;
%"GND"
"1","(-5350,8375)","0","logical_power","I73";
;
HDL_POWER"GND"
CDS_LIB"logical_power"
SIZE"1B";
"A<SIZE-1..0>\NAC"14;
%"Q_CAP"
"1","(-5350,8775)","0","pure_quanta","I74";
;
PART_NUMBER"CH4106K1B01"
PACK_TYPE"C0402"
VOLTAGE"50V"
MATERIAL"X7R"
VALUE"100NF"
ROOM"NIC1_P12V_MPS_MAM_BOM3"
LOCATION"PC2156"
ROOM1"NIC1_P12V_MPS_TIC_BOM4"
CDS_LIB"pure_quanta"
TOLERANCE"10%"
$SEC"1"
CDS_SEC"1";
"B"
$PN"2"14;
"A"
$PN"1"24;
%"Q_RES"
"1","(-5425,9150)","0","pure_quanta","I75";
;
PART_NUMBER"CS31002FB08"
TOLERANCE"1%"
VALUE"10K"
MATERIAL"CHIP"
PACK_TYPE"0402LF"
ROOM"NIC1_P12V_MPS_MAM_BOM3"
WATTAGE"1/16W"
LOCATION"PR3839"
ROOM1"NIC1_P12V_MPS_TIC_BOM4"
CDS_LIB"pure_quanta"
$SEC"1"
CDS_SEC"1";
"B"
$PN"2"2;
"A"
$PN"1"30;
%"Q_RES"
"2","(-5950,10225)","0","pure_quanta","I76";
;
PART_NUMBER"CS31002FB08"
VALUE"10K"
TOLERANCE"1%"
ROOM"NIC1_P12V_MPS_MAM_BOM3"
MATERIAL"CHIP"
WATTAGE"1/16W"
PACK_TYPE"0402LF"
$LOCATION"R4532"
ROOM1"NIC1_P12V_MPS_TIC_BOM4"
CDS_LIB"pure_quanta"
CDS_LOCATION"R4532"
$SEC"1"
CDS_SEC"1";
"A"
$PN"1"3;
"B"
$PN"2"23;
%"Q_RES"
"2","(-5425,9625)","0","pure_quanta","I77";
;
PART_NUMBER"CS11002FB07"
VALUE"100"
TOLERANCE"1%"
MATERIAL"EMPTY"
WATTAGE"1/16W"
PACK_TYPE"0402LF"
LOCATION"PR3838"
CDS_LIB"pure_quanta"
$SEC"1"
CDS_SEC"1";
"A"
$PN"1"5;
"B"
$PN"2"29;
%"VCCAUX15"
"1","(-4800,9200)","0","logical_power","I80";
;
HDL_POWER"P3V3_AUX"
CDS_LIB"logical_power";
"A"2;
%"Q_RES"
"1","(-4000,8450)","0","pure_quanta","I81";
;
PART_NUMBER"CS00002JB13"
ROOM1"NIC1_P12V_MPS_TIC_BOM4"
WATTAGE"1/16W"
PACK_TYPE"0402LF"
TOLERANCE"5%"
VALUE"0"
MATERIAL"CHIP"
$LOCATION"R3872"
CDS_LIB"pure_quanta"
CDS_LOCATION"R3872"
$SEC"1"
CDS_SEC"1";
"B"
$PN"2"26;
"A"
$PN"1"24;
%"Q_RES"
"1","(-4000,8625)","0","pure_quanta","I82";
;
PART_NUMBER"CS00002JB13"
TOLERANCE"5%"
VALUE"0"
MATERIAL"EMPTY"
WATTAGE"1/16W"
ROOM"NIC1_P12V_MPS_MAM_BOM3"
PACK_TYPE"0402LF"
$LOCATION"R3871"
CDS_LIB"pure_quanta"
CDS_LOCATION"R3871"
$SEC"1"
CDS_SEC"1";
"B"
$PN"2"27;
"A"
$PN"1"24;
%"Q_RES"
"2","(-4425,9125)","0","pure_quanta","I83";
;
PART_NUMBER"CS31002FB08"
TOLERANCE"1%"
VALUE"10K"
MATERIAL"CHIP"
ROOM"NIC1_P12V_MPS_MAM_BOM3"
WATTAGE"1/16W"
PACK_TYPE"0402LF"
LOCATION"PR3842"
ROOM1"NIC1_P12V_MPS_TIC_BOM4"
CDS_LIB"pure_quanta"
$SEC"1"
CDS_SEC"1";
"A"
$PN"1"25;
"B"
$PN"2"15;
%"GND"
"1","(-4225,8800)","0","logical_power","I84";
;
HDL_POWER"GND"
CDS_LIB"logical_power"
SIZE"1B";
"A<SIZE-1..0>\NAC"15;
%"Q_RES"
"2","(-4825,9625)","0","pure_quanta","I85";
;
PART_NUMBER"CS37152FB05"
VALUE"71.5K"
MATERIAL"EMPTY"
TOLERANCE"1%"
PACK_TYPE"0402LF"
LOCATION"PR3840"
CDS_LIB"pure_quanta"
WATTAGE"1/16W"
$SEC"1"
CDS_SEC"1";
"A"
$PN"1"5;
"B"
$PN"2"25;
%"Q_RES"
"2","(-4425,9550)","0","pure_quanta","I86";
;
PART_NUMBER"CS41202FB05"
VALUE"120K"
ROOM"NIC1_P12V_MPS_MAM_BOM3"
PACK_TYPE"0402LF"
MATERIAL"CHIP"
TOLERANCE"1%"
WATTAGE"1/16W"
LOCATION"PR3841"
ROOM1"NIC1_P12V_MPS_TIC_BOM4"
CDS_LIB"pure_quanta"
$SEC"1"
CDS_SEC"1";
"A"
$PN"1"4;
"B"
$PN"2"25;
%"VCCAUX15"
"1","(-5950,10425)","0","logical_power","I87";
;
HDL_POWER"P3V3_AUX"
CDS_LIB"logical_power";
"A"3;
%"Q_CAP"
"1","(-3900,9125)","0","pure_quanta","I88";
;
PART_NUMBER"CH5223M1900"
VOLTAGE"16V"
VALUE"2.2UF"
TOLERANCE"20%"
PACK_TYPE"C0603"
MATERIAL"X7R"
ROOM"NIC1_P12V_MPS_MAM_BOM3"
LOCATION"PC2158"
ROOM1"NIC1_P12V_MPS_TIC_BOM4"
CDS_LIB"pure_quanta"
$SEC"1"
CDS_SEC"1";
"B"
$PN"2"15;
"A"
$PN"1"28;
%"Q_RES"
"2","(-3900,9550)","0","pure_quanta","I89";
;
PART_NUMBER"CS04993F909"
WATTAGE"1/10W"
ROOM"NIC1_P12V_MPS_MAM_BOM3"
VALUE"49.9"
TOLERANCE"1%"
MATERIAL"CHIP"
PACK_TYPE"0603LF"
LOCATION"PR3843"
ROOM1"NIC1_P12V_MPS_TIC_BOM4"
CDS_LIB"pure_quanta"
$SEC"1"
CDS_SEC"1";
"A"
$PN"1"4;
"B"
$PN"2"28;
%"UNIVERSAL_POWER"
"1","(-3900,9850)","0","logical_power","I90";
;
HDL_POWER"P12V_AUX"
CDS_LIB"logical_power";
"A"4;
%"Q_CAP"
"1","(-3550,9975)","2","pure_quanta","I91";
;
PART_NUMBER"CH4104K1B00"
ROOM"NIC1_P12V_MPS_MAM_BOM3"
VALUE"0.1UF"
VOLTAGE"25V"
TOLERANCE"10%"
MATERIAL"X7R"
PACK_TYPE"0402"
LOCATION"PC2160"
ROOM1"NIC1_P12V_MPS_TIC_BOM4"
CDS_LIB"pure_quanta"
$SEC"1"
CDS_SEC"1";
"B"
$PN"2"16;
"A"
$PN"1"5;
%"GND"
"1","(-3550,9700)","0","logical_power","I92";
;
HDL_POWER"GND"
SIZE"1B"
CDS_LIB"logical_power";
"A<SIZE-1..0>\NAC"16;
%"UNIVERSAL_POWER"
"1","(-3550,10250)","2","logical_power","I94";
;
HDL_POWER"P12V_OCP_SFF"
CDS_LIB"logical_power";
"A"5;
END.
